(kicad_pcb
	(version 20260206)
	(generator "pcbnew")
	(generator_version "10.0")
	(general
		(thickness 1.6)
		(legacy_teardrops no)
	)
	(paper "A4")
	(title_block
		(title "Wiwynn_Tioga_Pass_MB.brd")
		(comment 1 "Tioga Pass / footprints 3638-3644 of 4770")
	)
	(layers
		(0 "F.Cu" signal "TOP")
		(4 "In1.Cu" signal "L2GND")
		(6 "In2.Cu" signal "L3")
		(8 "In3.Cu" signal "L4GND")
		(10 "In4.Cu" signal "L5")
		(12 "In5.Cu" signal "L6GND")
		(14 "In6.Cu" signal "L7VCC")
		(16 "In7.Cu" signal "L8VCC")
		(18 "In8.Cu" signal "L9GND")
		(20 "In9.Cu" signal "L10")
		(22 "In10.Cu" signal "L11GND")
		(24 "In11.Cu" signal "L12")
		(26 "In12.Cu" signal "L13GND")
		(2 "B.Cu" signal "BOTTOM")
		(9 "F.Adhes" user "F.Adhesive")
		(11 "B.Adhes" user "B.Adhesive")
		(13 "F.Paste" user "Package Geometry/Pastemask Top")
		(15 "B.Paste" user "Package Geometry/Pastemask Bottom")
		(5 "F.SilkS" user "Ref Des/Silkscreen Top")
		(7 "B.SilkS" user "Ref Des/Silkscreen Bottom")
		(1 "F.Mask" user "Board Geometry/Soldermask Top")
		(3 "B.Mask" user "Board Geometry/Soldermask Bottom")
		(17 "Dwgs.User" user "User.Drawings")
		(19 "Cmts.User" user "User.Comments")
		(21 "Eco1.User" user "User.Eco1")
		(23 "Eco2.User" user "User.Eco2")
		(25 "Edge.Cuts" user "Board Geometry/Outline")
		(27 "Margin" user)
		(31 "F.CrtYd" user "Package Geometry/Place Bound Top")
		(29 "B.CrtYd" user "Package Geometry/Place Bound Bottom")
		(35 "F.Fab" user "Ref Des/Assembly Top")
		(33 "B.Fab" user "Ref Des/Assembly Bottom")
	)
	(footprint ""
		(layer "B.Cu")
		(at 338.7344 -17.272 -90)
		(property "Reference" "R3U2"
			(at 0 0 90)
			(layer "B.SilkS")
			(hide yes)
			(effects
				(font
					(size 1.27 1.27)
				)
				(justify mirror)
			)
		)
		(property "Value" ""
			(at 0 0 90)
			(layer "B.Fab")
			(effects
				(font
					(size 1.27 1.27)
				)
				(justify mirror)
			)
		)
		(duplicate_pad_numbers_are_jumpers no)
		(fp_rect
			(start 0.2794 0.9906)
			(end -0.2794 -0.1016)
			(stroke
				(width 0)
				(type default)
			)
			(fill no)
			(layer "B.CrtYd")
		)
		(fp_line
			(start -0.2794 0.9906)
			(end -0.2794 -0.1016)
			(stroke
				(width 0.1)
				(type default)
			)
			(layer "B.Fab")
		)
		(fp_line
			(start 0.2794 0.9906)
			(end -0.2794 0.9906)
			(stroke
				(width 0.1)
				(type default)
			)
			(layer "B.Fab")
		)
		(fp_line
			(start -0.2794 -0.1016)
			(end 0.2794 -0.1016)
			(stroke
				(width 0.1)
				(type default)
			)
			(layer "B.Fab")
		)
		(fp_line
			(start 0.2794 -0.1016)
			(end 0.2794 0.9906)
			(stroke
				(width 0.1)
				(type default)
			)
			(layer "B.Fab")
		)
		(pad "1" smd rect
			(at 0 0 90)
			(size 0.508 0.508)
			(layers "B.Cu" "B.Mask" "B.Paste")
			(net "PVCCIO_CPU0")
		)
		(pad "2" smd rect
			(at 0 0.889 90)
			(size 0.508 0.508)
			(layers "B.Cu" "B.Mask" "B.Paste")
			(net "SVID_DIO1_CPU0_R")
		)
		(zone
			(layer "B.Cu")
			(hatch none 0.5)
			(connect_pads
				(clearance 0)
			)
			(min_thickness 0.25)
			(keepout
				(tracks not_allowed)
				(vias allowed)
				(pads allowed)
				(copperpour not_allowed)
				(footprints allowed)
			)
			(placement
				(enabled no)
				(sheetname "")
			)
			(fill
				(thermal_gap 0.5)
				(thermal_bridge_width 0.5)
				(island_removal_mode 0)
			)
			(polygon
				(pts
					(xy 338.0994 -17.018) (xy 338.4804 -17.018) (xy 338.4804 -17.526) (xy 338.0994 -17.526)
				)
			)
		)
		(zone
			(layer "B.Cu")
			(hatch none 0.5)
			(connect_pads
				(clearance 0)
			)
			(min_thickness 0.25)
			(keepout
				(tracks allowed)
				(vias not_allowed)
				(pads allowed)
				(copperpour not_allowed)
				(footprints allowed)
			)
			(placement
				(enabled no)
				(sheetname "")
			)
			(fill
				(thermal_gap 0.5)
				(thermal_bridge_width 0.5)
				(island_removal_mode 0)
			)
			(polygon
				(pts
					(xy 338.0994 -17.018) (xy 338.4804 -17.018) (xy 338.4804 -17.526) (xy 338.0994 -17.526)
				)
			)
		)
	)
	(footprint ""
		(layer "B.Cu")
		(at 80.391 -65.151 -90)
		(property "Reference" "R8P3"
			(at 0 0 90)
			(layer "B.SilkS")
			(hide yes)
			(effects
				(font
					(size 1.27 1.27)
				)
				(justify mirror)
			)
		)
		(property "Value" ""
			(at 0 0 90)
			(layer "B.Fab")
			(effects
				(font
					(size 1.27 1.27)
				)
				(justify mirror)
			)
		)
		(duplicate_pad_numbers_are_jumpers no)
		(fp_poly
			(pts
				(xy 0.2794 -0.1016) (xy -0.2794 -0.1016) (xy -0.2794 0.9906) (xy 0.2794 0.9906)
			)
			(stroke
				(width 0)
				(type default)
			)
			(fill no)
			(layer "B.CrtYd")
		)
		(fp_line
			(start -0.2794 0.9906)
			(end -0.2794 -0.1016)
			(stroke
				(width 0.1)
				(type default)
			)
			(layer "B.Fab")
		)
		(fp_line
			(start 0.2794 0.9906)
			(end -0.2794 0.9906)
			(stroke
				(width 0.1)
				(type default)
			)
			(layer "B.Fab")
		)
		(fp_line
			(start -0.2794 -0.1016)
			(end 0.2794 -0.1016)
			(stroke
				(width 0.1)
				(type default)
			)
			(layer "B.Fab")
		)
		(fp_line
			(start 0.2794 -0.1016)
			(end 0.2794 0.9906)
			(stroke
				(width 0.1)
				(type default)
			)
			(layer "B.Fab")
		)
		(pad "1" smd rect
			(at 0 0 90)
			(size 0.508 0.508)
			(layers "B.Cu" "B.Mask" "B.Paste")
			(net "PD_CPU1_RSVD_TEST_2")
		)
		(pad "2" smd rect
			(at 0 0.889 90)
			(size 0.508 0.508)
			(layers "B.Cu" "B.Mask" "B.Paste")
			(net "GND")
		)
		(zone
			(layer "B.Cu")
			(hatch none 0.5)
			(connect_pads
				(clearance 0)
			)
			(min_thickness 0.25)
			(keepout
				(tracks not_allowed)
				(vias allowed)
				(pads allowed)
				(copperpour not_allowed)
				(footprints allowed)
			)
			(placement
				(enabled no)
				(sheetname "")
			)
			(fill
				(thermal_gap 0.5)
				(thermal_bridge_width 0.5)
				(island_removal_mode 0)
			)
			(polygon
				(pts
					(xy 79.756 -64.897) (xy 79.756 -65.405) (xy 80.137 -65.405) (xy 80.137 -64.897)
				)
			)
		)
		(zone
			(layer "B.Cu")
			(hatch none 0.5)
			(connect_pads
				(clearance 0)
			)
			(min_thickness 0.25)
			(keepout
				(tracks allowed)
				(vias not_allowed)
				(pads allowed)
				(copperpour not_allowed)
				(footprints allowed)
			)
			(placement
				(enabled no)
				(sheetname "")
			)
			(fill
				(thermal_gap 0.5)
				(thermal_bridge_width 0.5)
				(island_removal_mode 0)
			)
			(polygon
				(pts
					(xy 80.137 -64.897) (xy 80.137 -65.405) (xy 79.756 -65.405) (xy 79.756 -64.897)
				)
			)
		)
	)
	(footprint ""
		(layer "B.Cu")
		(at 372.4275 -93.853 90)
		(property "Reference" "R3P8"
			(at 0 0 90)
			(layer "B.SilkS")
			(hide yes)
			(effects
				(font
					(size 1.27 1.27)
				)
				(justify mirror)
			)
		)
		(property "Value" ""
			(at 0 0 90)
			(layer "B.Fab")
			(effects
				(font
					(size 1.27 1.27)
				)
				(justify mirror)
			)
		)
		(duplicate_pad_numbers_are_jumpers no)
		(fp_poly
			(pts
				(xy 0.2794 -0.1016) (xy -0.2794 -0.1016) (xy -0.2794 0.9906) (xy 0.2794 0.9906)
			)
			(stroke
				(width 0)
				(type default)
			)
			(fill no)
			(layer "B.CrtYd")
		)
		(fp_line
			(start 0.2794 -0.1016)
			(end 0.2794 0.9906)
			(stroke
				(width 0.1)
				(type default)
			)
			(layer "B.Fab")
		)
		(fp_line
			(start -0.2794 -0.1016)
			(end 0.2794 -0.1016)
			(stroke
				(width 0.1)
				(type default)
			)
			(layer "B.Fab")
		)
		(fp_line
			(start 0.2794 0.9906)
			(end -0.2794 0.9906)
			(stroke
				(width 0.1)
				(type default)
			)
			(layer "B.Fab")
		)
		(fp_line
			(start -0.2794 0.9906)
			(end -0.2794 -0.1016)
			(stroke
				(width 0.1)
				(type default)
			)
			(layer "B.Fab")
		)
		(pad "1" smd rect
			(at 0 0 270)
			(size 0.508 0.508)
			(layers "B.Cu" "B.Mask" "B.Paste")
			(net "P1V05_PCH_STBY")
		)
		(pad "2" smd rect
			(at 0 0.889 270)
			(size 0.508 0.508)
			(layers "B.Cu" "B.Mask" "B.Paste")
			(net "FM_PRSNT_2_6_N")
		)
		(zone
			(layer "B.Cu")
			(hatch none 0.5)
			(connect_pads
				(clearance 0)
			)
			(min_thickness 0.25)
			(keepout
				(tracks allowed)
				(vias not_allowed)
				(pads allowed)
				(copperpour not_allowed)
				(footprints allowed)
			)
			(placement
				(enabled no)
				(sheetname "")
			)
			(fill
				(thermal_gap 0.5)
				(thermal_bridge_width 0.5)
				(island_removal_mode 0)
			)
			(polygon
				(pts
					(xy 372.6815 -94.107) (xy 372.6815 -93.599) (xy 373.0625 -93.599) (xy 373.0625 -94.107)
				)
			)
		)
		(zone
			(layer "B.Cu")
			(hatch none 0.5)
			(connect_pads
				(clearance 0)
			)
			(min_thickness 0.25)
			(keepout
				(tracks not_allowed)
				(vias allowed)
				(pads allowed)
				(copperpour not_allowed)
				(footprints allowed)
			)
			(placement
				(enabled no)
				(sheetname "")
			)
			(fill
				(thermal_gap 0.5)
				(thermal_bridge_width 0.5)
				(island_removal_mode 0)
			)
			(polygon
				(pts
					(xy 373.0625 -94.107) (xy 373.0625 -93.599) (xy 372.6815 -93.599) (xy 372.6815 -94.107)
				)
			)
		)
	)
	(footprint ""
		(layer "B.Cu")
		(at 328.803 -55.626 90)
		(property "Reference" "C4R2"
			(at 0 0 90)
			(layer "B.SilkS")
			(hide yes)
			(effects
				(font
					(size 1.27 1.27)
				)
				(justify mirror)
			)
		)
		(property "Value" ""
			(at 0 0 90)
			(layer "B.Fab")
			(effects
				(font
					(size 1.27 1.27)
				)
				(justify mirror)
			)
		)
		(duplicate_pad_numbers_are_jumpers no)
		(fp_poly
			(pts
				(xy -0.3048 -0.1016) (xy -0.3048 0.9906) (xy 0.3048 0.9906) (xy 0.3048 -0.1016)
			)
			(stroke
				(width 0)
				(type default)
			)
			(fill no)
			(layer "B.CrtYd")
		)
		(fp_line
			(start 0.3048 -0.1016)
			(end 0.3048 0.9906)
			(stroke
				(width 0.1)
				(type default)
			)
			(layer "B.Fab")
		)
		(fp_line
			(start -0.3048 -0.1016)
			(end 0.3048 -0.1016)
			(stroke
				(width 0.1)
				(type default)
			)
			(layer "B.Fab")
		)
		(fp_line
			(start 0.3048 0.9906)
			(end -0.3048 0.9906)
			(stroke
				(width 0.1)
				(type default)
			)
			(layer "B.Fab")
		)
		(fp_line
			(start -0.3048 0.9906)
			(end -0.3048 -0.1016)
			(stroke
				(width 0.1)
				(type default)
			)
			(layer "B.Fab")
		)
		(pad "1" smd rect
			(at 0 0 270)
			(size 0.508 0.508)
			(layers "B.Cu" "B.Mask" "B.Paste")
			(net "JTAG_MCP_CPU0_TDI_R")
		)
		(pad "2" smd rect
			(at 0 0.889 270)
			(size 0.508 0.508)
			(layers "B.Cu" "B.Mask" "B.Paste")
			(net "GND")
		)
		(zone
			(layer "B.Cu")
			(hatch none 0.5)
			(connect_pads
				(clearance 0)
			)
			(min_thickness 0.25)
			(keepout
				(tracks allowed)
				(vias not_allowed)
				(pads allowed)
				(copperpour not_allowed)
				(footprints allowed)
			)
			(placement
				(enabled no)
				(sheetname "")
			)
			(fill
				(thermal_gap 0.5)
				(thermal_bridge_width 0.5)
				(island_removal_mode 0)
			)
			(polygon
				(pts
					(xy 329.057 -55.88) (xy 329.057 -55.372) (xy 329.438 -55.372) (xy 329.438 -55.88)
				)
			)
		)
		(zone
			(layer "B.Cu")
			(hatch none 0.5)
			(connect_pads
				(clearance 0)
			)
			(min_thickness 0.25)
			(keepout
				(tracks not_allowed)
				(vias allowed)
				(pads allowed)
				(copperpour not_allowed)
				(footprints allowed)
			)
			(placement
				(enabled no)
				(sheetname "")
			)
			(fill
				(thermal_gap 0.5)
				(thermal_bridge_width 0.5)
				(island_removal_mode 0)
			)
			(polygon
				(pts
					(xy 329.438 -55.88) (xy 329.438 -55.372) (xy 329.057 -55.372) (xy 329.057 -55.88)
				)
			)
		)
	)
	(footprint ""
		(layer "B.Cu")
		(at 385.6228 -102.489 -90)
		(property "Reference" "C3N29"
			(at 0 0 90)
			(layer "B.SilkS")
			(hide yes)
			(effects
				(font
					(size 1.27 1.27)
				)
				(justify mirror)
			)
		)
		(property "Value" ""
			(at 0 0 90)
			(layer "B.Fab")
			(effects
				(font
					(size 1.27 1.27)
				)
				(justify mirror)
			)
		)
		(duplicate_pad_numbers_are_jumpers no)
		(fp_rect
			(start 0.2794 0.9144)
			(end -0.2794 -0.1143)
			(stroke
				(width 0)
				(type default)
			)
			(fill no)
			(layer "B.CrtYd")
		)
		(fp_line
			(start -0.2794 0.9144)
			(end 0.2794 0.9144)
			(stroke
				(width 0.1)
				(type default)
			)
			(layer "B.Fab")
		)
		(fp_line
			(start 0.2794 0.9144)
			(end 0.2794 -0.1143)
			(stroke
				(width 0.1)
				(type default)
			)
			(layer "B.Fab")
		)
		(fp_line
			(start -0.2794 -0.1143)
			(end -0.2794 0.9144)
			(stroke
				(width 0.1)
				(type default)
			)
			(layer "B.Fab")
		)
		(fp_line
			(start 0.2794 -0.1143)
			(end -0.2794 -0.1143)
			(stroke
				(width 0.1)
				(type default)
			)
			(layer "B.Fab")
		)
		(pad "1" smd custom
			(at 0 0 180)
			(size 0.10414 0.10414)
			(layers "B.Cu" "B.Mask" "B.Paste")
			(net "A_PVCCRTC_EXT_CAP")
			(options
				(clearance outline)
				(anchor circle)
			)
			(primitives
				(gr_poly
					(pts
						(xy -0.20828 -0.08636) (xy -0.20828 0.08636) (xy -0.08636 0.20828) (xy 0.086614 0.20828) (xy 0.20828 0.086614)
						(xy 0.20828 -0.08636) (xy 0.08636 -0.20828) (xy -0.08636 -0.20828)
					)
					(width 0)
					(fill yes)
				)
			)
		)
		(pad "2" smd custom
			(at 0 0.8001 180)
			(size 0.10414 0.10414)
			(layers "B.Cu" "B.Mask" "B.Paste")
			(net "GND")
			(options
				(clearance outline)
				(anchor circle)
			)
			(primitives
				(gr_poly
					(pts
						(xy -0.20828 -0.08636) (xy -0.20828 0.08636) (xy -0.08636 0.20828) (xy 0.086614 0.20828) (xy 0.20828 0.086614)
						(xy 0.20828 -0.08636) (xy 0.08636 -0.20828) (xy -0.08636 -0.20828)
					)
					(width 0)
					(fill yes)
				)
			)
		)
		(zone
			(layer "B.Cu")
			(hatch none 0.5)
			(connect_pads
				(clearance 0)
			)
			(min_thickness 0.25)
			(keepout
				(tracks not_allowed)
				(vias allowed)
				(pads allowed)
				(copperpour not_allowed)
				(footprints allowed)
			)
			(placement
				(enabled no)
				(sheetname "")
			)
			(fill
				(thermal_gap 0.5)
				(thermal_bridge_width 0.5)
				(island_removal_mode 0)
			)
			(polygon
				(pts
					(xy 385.41325 -102.40137) (xy 385.03225 -102.40137) (xy 385.03225 -102.57663) (xy 385.41325 -102.576884)
				)
			)
		)
		(zone
			(layer "B.Cu")
			(hatch none 0.5)
			(connect_pads
				(clearance 0)
			)
			(min_thickness 0.25)
			(keepout
				(tracks allowed)
				(vias not_allowed)
				(pads allowed)
				(copperpour not_allowed)
				(footprints allowed)
			)
			(placement
				(enabled no)
				(sheetname "")
			)
			(fill
				(thermal_gap 0.5)
				(thermal_bridge_width 0.5)
				(island_removal_mode 0)
			)
			(polygon
				(pts
					(xy 385.41325 -102.40137) (xy 385.03225 -102.40137) (xy 385.03225 -102.57663) (xy 385.41325 -102.576884)
				)
			)
		)
	)
	(footprint ""
		(layer "B.Cu")
		(at 424.815 -27.0002 180)
		(property "Reference" "R2W5"
			(at 0.8382 -0.67818 180)
			(unlocked yes)
			(layer "B.SilkS")
			(effects
				(font
					(size 0.4064 0.254)
					(thickness 0.1524)
				)
				(justify left mirror)
			)
		)
		(property "Value" ""
			(at 0 0 0)
			(layer "B.Fab")
			(effects
				(font
					(size 1.27 1.27)
				)
				(justify mirror)
			)
		)
		(duplicate_pad_numbers_are_jumpers no)
		(fp_poly
			(pts
				(xy 0.2794 -0.1016) (xy -0.2794 -0.1016) (xy -0.2794 0.9906) (xy 0.2794 0.9906)
			)
			(stroke
				(width 0)
				(type default)
			)
			(fill no)
			(layer "B.CrtYd")
		)
		(fp_line
			(start 0.2794 0.9906)
			(end -0.2794 0.9906)
			(stroke
				(width 0.1)
				(type default)
			)
			(layer "B.Fab")
		)
		(fp_line
			(start 0.2794 -0.1016)
			(end 0.2794 0.9906)
			(stroke
				(width 0.1)
				(type default)
			)
			(layer "B.Fab")
		)
		(fp_line
			(start -0.2794 0.9906)
			(end -0.2794 -0.1016)
			(stroke
				(width 0.1)
				(type default)
			)
			(layer "B.Fab")
		)
		(fp_line
			(start -0.2794 -0.1016)
			(end 0.2794 -0.1016)
			(stroke
				(width 0.1)
				(type default)
			)
			(layer "B.Fab")
		)
		(pad "1" smd rect
			(at 0 0)
			(size 0.508 0.508)
			(layers "B.Cu" "B.Mask" "B.Paste")
			(net "FM_PMBUS_ALERT_BUF_EN_R3_N")
		)
		(pad "2" smd rect
			(at 0 0.889)
			(size 0.508 0.508)
			(layers "B.Cu" "B.Mask" "B.Paste")
			(net "FM_PMBUS_ALERT_BUF_EN_N")
		)
		(zone
			(layer "B.Cu")
			(hatch none 0.5)
			(connect_pads
				(clearance 0)
			)
			(min_thickness 0.25)
			(keepout
				(tracks not_allowed)
				(vias allowed)
				(pads allowed)
				(copperpour not_allowed)
				(footprints allowed)
			)
			(placement
				(enabled no)
				(sheetname "")
			)
			(fill
				(thermal_gap 0.5)
				(thermal_bridge_width 0.5)
				(island_removal_mode 0)
			)
			(polygon
				(pts
					(xy 424.561 -27.6352) (xy 425.069 -27.6352) (xy 425.069 -27.2542) (xy 424.561 -27.2542)
				)
			)
		)
		(zone
			(layer "B.Cu")
			(hatch none 0.5)
			(connect_pads
				(clearance 0)
			)
			(min_thickness 0.25)
			(keepout
				(tracks allowed)
				(vias not_allowed)
				(pads allowed)
				(copperpour not_allowed)
				(footprints allowed)
			)
			(placement
				(enabled no)
				(sheetname "")
			)
			(fill
				(thermal_gap 0.5)
				(thermal_bridge_width 0.5)
				(island_removal_mode 0)
			)
			(polygon
				(pts
					(xy 424.561 -27.2542) (xy 425.069 -27.2542) (xy 425.069 -27.6352) (xy 424.561 -27.6352)
				)
			)
		)
	)
	(footprint ""
		(layer "B.Cu")
		(at 185.42 -145.923 -90)
		(property "Reference" "R6L9"
			(at 0 0 90)
			(layer "B.SilkS")
			(hide yes)
			(effects
				(font
					(size 1.27 1.27)
				)
				(justify mirror)
			)
		)
		(property "Value" ""
			(at 0 0 90)
			(layer "B.Fab")
			(effects
				(font
					(size 1.27 1.27)
				)
				(justify mirror)
			)
		)
		(duplicate_pad_numbers_are_jumpers no)
		(fp_rect
			(start -0.2794 0.9906)
			(end 0.2794 -0.1016)
			(stroke
				(width 0)
				(type default)
			)
			(fill no)
			(layer "B.CrtYd")
		)
		(fp_line
			(start -0.2794 0.9906)
			(end -0.2794 -0.1016)
			(stroke
				(width 0.1)
				(type default)
			)
			(layer "B.Fab")
		)
		(fp_line
			(start 0.2794 0.9906)
			(end -0.2794 0.9906)
			(stroke
				(width 0.1)
				(type default)
			)
			(layer "B.Fab")
		)
		(fp_line
			(start -0.2794 -0.1016)
			(end 0.2794 -0.1016)
			(stroke
				(width 0.1)
				(type default)
			)
			(layer "B.Fab")
		)
		(fp_line
			(start 0.2794 -0.1016)
			(end 0.2794 0.9906)
			(stroke
				(width 0.1)
				(type default)
			)
			(layer "B.Fab")
		)
		(pad "1" smd rect
			(at 0 0 90)
			(size 0.508 0.508)
			(layers "B.Cu" "B.Mask" "B.Paste")
			(net "P3V3")
		)
		(pad "2" smd rect
			(at 0 0.889 90)
			(size 0.508 0.508)
			(layers "B.Cu" "B.Mask" "B.Paste")
			(net "PWRGD_PVTT_DEF_CPU0_R")
		)
		(zone
			(layer "B.Cu")
			(hatch none 0.5)
			(connect_pads
				(clearance 0)
			)
			(min_thickness 0.25)
			(keepout
				(tracks allowed)
				(vias not_allowed)
				(pads allowed)
				(copperpour not_allowed)
				(footprints allowed)
			)
			(placement
				(enabled no)
				(sheetname "")
			)
			(fill
				(thermal_gap 0.5)
				(thermal_bridge_width 0.5)
				(island_removal_mode 0)
			)
			(polygon
				(pts
					(xy 184.785 -146.177) (xy 184.785 -145.669) (xy 185.166 -145.669) (xy 185.166 -146.177)
				)
			)
		)
		(zone
			(layer "B.Cu")
			(hatch none 0.5)
			(connect_pads
				(clearance 0)
			)
			(min_thickness 0.25)
			(keepout
				(tracks not_allowed)
				(vias allowed)
				(pads allowed)
				(copperpour not_allowed)
				(footprints allowed)
			)
			(placement
				(enabled no)
				(sheetname "")
			)
			(fill
				(thermal_gap 0.5)
				(thermal_bridge_width 0.5)
				(island_removal_mode 0)
			)
			(polygon
				(pts
					(xy 184.785 -146.177) (xy 184.785 -145.669) (xy 185.166 -145.669) (xy 185.166 -146.177)
				)
			)
		)
	)
)
